(kicad_pcb
	(version 20260206)
	(generator "pcbnew")
	(generator_version "10.0")
	(general
		(thickness 1.6)
		(legacy_teardrops no)
	)
	(paper "A4")
	(title_block
		(title "v1-chassis-manager — T6M_CM_d_v01_1031_1645.brd")
		(comment 1 "Open CloudServer (Microsoft) / footprints 1460-1469 of 2512")
	)
	(layers
		(0 "F.Cu" signal "TOP")
		(4 "In1.Cu" signal "GND1")
		(6 "In2.Cu" signal "IN1")
		(8 "In3.Cu" signal "VCC1")
		(10 "In4.Cu" signal "VCC2")
		(12 "In5.Cu" signal "GND2")
		(14 "In6.Cu" signal "IN2")
		(16 "In7.Cu" signal "IN3")
		(18 "In8.Cu" signal "GND3")
		(2 "B.Cu" signal "BOTTOM")
		(9 "F.Adhes" user "F.Adhesive")
		(11 "B.Adhes" user "B.Adhesive")
		(13 "F.Paste" user "Package Geometry/Pastemask Top")
		(15 "B.Paste" user "Package Geometry/Pastemask Bottom")
		(5 "F.SilkS" user "Ref Des/Silkscreen Top")
		(7 "B.SilkS" user "Ref Des/Silkscreen Bottom")
		(1 "F.Mask" user "Board Geometry/Soldermask Top")
		(3 "B.Mask" user "Board Geometry/Soldermask Bottom")
		(17 "Dwgs.User" user "User.Drawings")
		(19 "Cmts.User" user "User.Comments")
		(21 "Eco1.User" user "User.Eco1")
		(23 "Eco2.User" user "User.Eco2")
		(25 "Edge.Cuts" user "Board Geometry/Outline")
		(27 "Margin" user)
		(31 "F.CrtYd" user "Package Geometry/Place Bound Top")
		(29 "B.CrtYd" user "Package Geometry/Place Bound Bottom")
		(35 "F.Fab" user "Ref Des/Assembly Top")
		(33 "B.Fab" user "Ref Des/Assembly Bottom")
	)
	(footprint ""
		(layer "F.Cu")
		(at 105.737152 -129.483358 90)
		(property "Reference" "PR48"
			(at -3.211322 -7.332472 90)
			(unlocked yes)
			(layer "F.SilkS")
			(effects
				(font
					(size 0.7874 0.5842)
					(thickness 0.1524)
				)
			)
		)
		(property "Value" ""
			(at 0 0 90)
			(layer "F.Fab")
			(effects
				(font
					(size 1.27 1.27)
				)
			)
		)
		(duplicate_pad_numbers_are_jumpers no)
		(fp_line
			(start 1.2954 -0.5842)
			(end 1.2954 0.5842)
			(stroke
				(width 0.1524)
				(type default)
			)
			(layer "F.SilkS")
		)
		(fp_line
			(start -1.2954 -0.5842)
			(end 1.2954 -0.5842)
			(stroke
				(width 0.1524)
				(type default)
			)
			(layer "F.SilkS")
		)
		(fp_line
			(start 1.2954 0.5842)
			(end -1.2954 0.5842)
			(stroke
				(width 0.1524)
				(type default)
			)
			(layer "F.SilkS")
		)
		(fp_line
			(start -1.2954 0.5842)
			(end -1.2954 -0.5842)
			(stroke
				(width 0.1524)
				(type default)
			)
			(layer "F.SilkS")
		)
		(fp_poly
			(pts
				(xy 1.143 -0.3556) (xy 1.143 0.3556) (xy 0.8636 0.3556) (xy 0.8636 0.4572) (xy -0.8636 0.4572) (xy -0.8636 0.4318)
				(xy -0.8636 0.3556) (xy -1.143 0.3556) (xy -1.143 -0.3556) (xy -0.8636 -0.3556) (xy -0.8636 -0.4572)
				(xy 0.8636 -0.4572) (xy 0.8636 -0.3556)
			)
			(stroke
				(width 0)
				(type default)
			)
			(fill no)
			(layer "F.CrtYd")
		)
		(pad "1" smd rect
			(at 0.7366 0 180)
			(size 0.7112 0.8128)
			(layers "F.Cu" "F.Mask" "F.Paste")
			(net "VR_PVCCP_NODE1_PVCC")
		)
		(pad "2" smd rect
			(at -0.7366 0 180)
			(size 0.7112 0.8128)
			(layers "F.Cu" "F.Mask" "F.Paste")
			(net "P5V_STB_NODE1")
		)
	)
	(footprint ""
		(layer "F.Cu")
		(at 114.697002 -25.82672 -90)
		(property "Reference" "J24"
			(at 0.06858 4.35864 0)
			(unlocked yes)
			(layer "F.SilkS")
			(effects
				(font
					(size 0.7874 0.5842)
					(thickness 0.1524)
				)
				(justify left)
			)
		)
		(property "Value" ""
			(at 0 0 270)
			(layer "F.Fab")
			(effects
				(font
					(size 1.27 1.27)
				)
			)
		)
		(duplicate_pad_numbers_are_jumpers no)
		(fp_poly
			(pts
				(xy -0.360426 0.359156) (xy -0.360426 -0.381) (xy 0.3556 -0.381) (xy 0.3556 1.905) (xy -0.360426 1.905)
			)
			(stroke
				(width 0)
				(type default)
			)
			(fill no)
			(layer "F.CrtYd")
		)
		(pad "1" smd custom
			(at 0 0 270)
			(size 0.1778 0.1778)
			(layers "F.Cu" "F.Mask" "F.Paste")
			(net "PV_VTT_DDR_NODE1")
			(options
				(clearance outline)
				(anchor circle)
			)
			(primitives
				(gr_poly
					(pts
						(xy -0.127 0.9398) (xy -0.127 -0.127) (xy -0.3556 -0.127) (xy -0.3556 -0.9398) (xy 0.3556 -0.9398)
						(xy 0.3556 -0.127) (xy 0.127 -0.127) (xy 0.127 0.9398)
					)
					(width 0)
					(fill yes)
				)
			)
		)
		(pad "2" smd rect
			(at 0 1.4986 90)
			(size 0.7112 0.8128)
			(layers "F.Cu" "F.Mask" "F.Paste")
			(net "PV_VTT_DDR_NODE1_VOSNS")
		)
		(zone
			(layer "F.Cu")
			(hatch none 0.5)
			(connect_pads
				(clearance 0)
			)
			(min_thickness 0.25)
			(keepout
				(tracks allowed)
				(vias not_allowed)
				(pads allowed)
				(copperpour not_allowed)
				(footprints allowed)
			)
			(placement
				(enabled no)
				(sheetname "")
			)
			(fill
				(thermal_gap 0.5)
				(thermal_bridge_width 0.5)
				(island_removal_mode 0)
			)
			(polygon
				(pts
					(xy 112.741202 -25.42032) (xy 115.128802 -25.42032) (xy 115.128802 -26.237946) (xy 112.741202 -26.237946)
				)
			)
		)
	)
	(footprint ""
		(layer "F.Cu")
		(at 123.70816 -171.603416)
		(property "Reference" "R682"
			(at 30.127448 47.916338 0)
			(unlocked yes)
			(layer "F.SilkS")
			(effects
				(font
					(size 0.7874 0.5842)
					(thickness 0.1524)
				)
				(justify left)
			)
		)
		(property "Value" ""
			(at 0 0 0)
			(layer "F.Fab")
			(effects
				(font
					(size 1.27 1.27)
				)
			)
		)
		(duplicate_pad_numbers_are_jumpers no)
		(fp_line
			(start -0.7874 -0.4064)
			(end 0.7874 -0.4064)
			(stroke
				(width 0.1524)
				(type default)
			)
			(layer "F.SilkS")
		)
		(fp_line
			(start -0.7874 0.4064)
			(end -0.7874 -0.4064)
			(stroke
				(width 0.1524)
				(type default)
			)
			(layer "F.SilkS")
		)
		(fp_line
			(start 0.7874 -0.4064)
			(end 0.7874 0.4064)
			(stroke
				(width 0.1524)
				(type default)
			)
			(layer "F.SilkS")
		)
		(fp_line
			(start 0.7874 0.4064)
			(end -0.7874 0.4064)
			(stroke
				(width 0.1524)
				(type default)
			)
			(layer "F.SilkS")
		)
		(fp_poly
			(pts
				(xy -0.508 0.2794) (xy -0.508 0.2286) (xy -0.635 0.2286) (xy -0.635 -0.254) (xy -0.5334 -0.254)
				(xy -0.5334 -0.2794) (xy 0.5334 -0.2794) (xy 0.5334 -0.254) (xy 0.635 -0.254) (xy 0.635 0.254) (xy 0.5334 0.254)
				(xy 0.5334 0.2794)
			)
			(stroke
				(width 0)
				(type default)
			)
			(fill no)
			(layer "F.CrtYd")
		)
		(pad "1" smd rect
			(at 0.40005 0)
			(size 0.4572 0.508)
			(layers "F.Cu" "F.Mask" "F.Paste")
			(net "GND")
		)
		(pad "2" smd rect
			(at -0.40005 0)
			(size 0.4572 0.508)
			(layers "F.Cu" "F.Mask" "F.Paste")
			(net "N21699069")
		)
	)
	(footprint ""
		(layer "F.Cu")
		(at 36.707572 -73.402698)
		(property "Reference" "R45"
			(at -3.279394 0.319278 0)
			(unlocked yes)
			(layer "F.SilkS")
			(effects
				(font
					(size 0.7874 0.5842)
					(thickness 0.1524)
				)
				(justify left)
			)
		)
		(property "Value" ""
			(at 0 0 0)
			(layer "F.Fab")
			(effects
				(font
					(size 1.27 1.27)
				)
			)
		)
		(duplicate_pad_numbers_are_jumpers no)
		(fp_line
			(start -0.7874 -0.4064)
			(end 0.7874 -0.4064)
			(stroke
				(width 0.1524)
				(type default)
			)
			(layer "F.SilkS")
		)
		(fp_line
			(start -0.7874 0.4064)
			(end -0.7874 -0.4064)
			(stroke
				(width 0.1524)
				(type default)
			)
			(layer "F.SilkS")
		)
		(fp_line
			(start 0.7874 -0.4064)
			(end 0.7874 0.4064)
			(stroke
				(width 0.1524)
				(type default)
			)
			(layer "F.SilkS")
		)
		(fp_line
			(start 0.7874 0.4064)
			(end -0.7874 0.4064)
			(stroke
				(width 0.1524)
				(type default)
			)
			(layer "F.SilkS")
		)
		(fp_poly
			(pts
				(xy -0.508 0.2794) (xy -0.508 0.2286) (xy -0.635 0.2286) (xy -0.635 -0.254) (xy -0.5334 -0.254)
				(xy -0.5334 -0.2794) (xy 0.5334 -0.2794) (xy 0.5334 -0.254) (xy 0.635 -0.254) (xy 0.635 0.254) (xy 0.5334 0.254)
				(xy 0.5334 0.2794)
			)
			(stroke
				(width 0)
				(type default)
			)
			(fill no)
			(layer "F.CrtYd")
		)
		(pad "1" smd rect
			(at 0.40005 0)
			(size 0.4572 0.508)
			(layers "F.Cu" "F.Mask" "F.Paste")
			(net "PD_CPU_NODE1_RP1_PERP")
		)
		(pad "2" smd rect
			(at -0.40005 0)
			(size 0.4572 0.508)
			(layers "F.Cu" "F.Mask" "F.Paste")
			(net "GND")
		)
	)
	(footprint ""
		(layer "F.Cu")
		(at 115.863878 -18.992596)
		(property "Reference" "R1126"
			(at 5.284978 2.044954 90)
			(unlocked yes)
			(layer "F.SilkS")
			(effects
				(font
					(size 0.7874 0.5842)
					(thickness 0.1524)
				)
				(justify left)
			)
		)
		(property "Value" ""
			(at 0 0 0)
			(layer "F.Fab")
			(effects
				(font
					(size 1.27 1.27)
				)
			)
		)
		(duplicate_pad_numbers_are_jumpers no)
		(fp_line
			(start -0.7874 -0.4064)
			(end 0.7874 -0.4064)
			(stroke
				(width 0.1524)
				(type default)
			)
			(layer "F.SilkS")
		)
		(fp_line
			(start -0.7874 0.4064)
			(end -0.7874 -0.4064)
			(stroke
				(width 0.1524)
				(type default)
			)
			(layer "F.SilkS")
		)
		(fp_line
			(start 0.7874 -0.4064)
			(end 0.7874 0.4064)
			(stroke
				(width 0.1524)
				(type default)
			)
			(layer "F.SilkS")
		)
		(fp_line
			(start 0.7874 0.4064)
			(end -0.7874 0.4064)
			(stroke
				(width 0.1524)
				(type default)
			)
			(layer "F.SilkS")
		)
		(fp_poly
			(pts
				(xy -0.508 0.2794) (xy -0.508 0.2286) (xy -0.635 0.2286) (xy -0.635 -0.254) (xy -0.5334 -0.254)
				(xy -0.5334 -0.2794) (xy 0.5334 -0.2794) (xy 0.5334 -0.254) (xy 0.635 -0.254) (xy 0.635 0.254) (xy 0.5334 0.254)
				(xy 0.5334 0.2794)
			)
			(stroke
				(width 0)
				(type default)
			)
			(fill no)
			(layer "F.CrtYd")
		)
		(pad "1" smd rect
			(at 0.40005 0)
			(size 0.4572 0.508)
			(layers "F.Cu" "F.Mask" "F.Paste")
			(net "P3V3_STB_NODE1")
		)
		(pad "2" smd rect
			(at -0.40005 0)
			(size 0.4572 0.508)
			(layers "F.Cu" "F.Mask" "F.Paste")
			(net "PWRGD_NODE1_PVTT_DDR_PG")
		)
	)
	(footprint ""
		(layer "F.Cu")
		(at 75.766422 -17.664176 90)
		(property "Reference" "C173"
			(at -3.058414 5.94106 90)
			(unlocked yes)
			(layer "F.SilkS")
			(effects
				(font
					(size 0.7874 0.5842)
					(thickness 0.1524)
				)
			)
		)
		(property "Value" ""
			(at 0 0 90)
			(layer "F.Fab")
			(effects
				(font
					(size 1.27 1.27)
				)
			)
		)
		(duplicate_pad_numbers_are_jumpers no)
		(fp_line
			(start 1.2954 -0.5842)
			(end 1.2954 0.5842)
			(stroke
				(width 0.1524)
				(type default)
			)
			(layer "F.SilkS")
		)
		(fp_line
			(start 0 -0.5842)
			(end 0 0.5842)
			(stroke
				(width 0.1524)
				(type default)
			)
			(layer "F.SilkS")
		)
		(fp_line
			(start -1.2954 -0.5842)
			(end 1.2954 -0.5842)
			(stroke
				(width 0.1524)
				(type default)
			)
			(layer "F.SilkS")
		)
		(fp_line
			(start 1.2954 0.5842)
			(end -1.2954 0.5842)
			(stroke
				(width 0.1524)
				(type default)
			)
			(layer "F.SilkS")
		)
		(fp_line
			(start -1.2954 0.5842)
			(end -1.2954 -0.5842)
			(stroke
				(width 0.1524)
				(type default)
			)
			(layer "F.SilkS")
		)
		(fp_poly
			(pts
				(xy 0.8636 -0.4572) (xy 0.8636 -0.3556) (xy 1.143 -0.3556) (xy 1.143 0.3556) (xy 0.8636 0.3556)
				(xy 0.8636 0.4572) (xy -0.8636 0.4572) (xy -0.8636 0.3556) (xy -1.143 0.3556) (xy -1.143 -0.3556)
				(xy -0.8636 -0.3556) (xy -0.8636 -0.4572)
			)
			(stroke
				(width 0)
				(type default)
			)
			(fill no)
			(layer "F.CrtYd")
		)
		(fp_line
			(start 0.884936 -0.504952)
			(end 0.884936 0.504952)
			(stroke
				(width 0.1)
				(type default)
			)
			(layer "F.Fab")
		)
		(fp_line
			(start -0.884936 -0.504952)
			(end 0.884936 -0.504952)
			(stroke
				(width 0.1)
				(type default)
			)
			(layer "F.Fab")
		)
		(fp_line
			(start 0.884936 0.504952)
			(end -0.884936 0.504952)
			(stroke
				(width 0.1)
				(type default)
			)
			(layer "F.Fab")
		)
		(fp_line
			(start -0.884936 0.504952)
			(end -0.884936 -0.504952)
			(stroke
				(width 0.1)
				(type default)
			)
			(layer "F.Fab")
		)
		(pad "1" smd rect
			(at 0.7366 0 180)
			(size 0.7112 0.8128)
			(layers "F.Cu" "F.Mask" "F.Paste")
			(net "PV_VDDR_NODE1")
		)
		(pad "2" smd rect
			(at -0.7366 0 180)
			(size 0.7112 0.8128)
			(layers "F.Cu" "F.Mask" "F.Paste")
			(net "GND")
		)
	)
	(footprint ""
		(layer "F.Cu")
		(at 56.24576 -185.205624 -90)
		(property "Reference" "R952"
			(at -4.006088 0.027178 90)
			(unlocked yes)
			(layer "F.SilkS")
			(effects
				(font
					(size 0.7874 0.5842)
					(thickness 0.1524)
				)
				(justify left)
			)
		)
		(property "Value" ""
			(at 0 0 270)
			(layer "F.Fab")
			(effects
				(font
					(size 1.27 1.27)
				)
			)
		)
		(duplicate_pad_numbers_are_jumpers no)
		(fp_line
			(start -0.7874 0.4064)
			(end -0.7874 -0.4064)
			(stroke
				(width 0.1524)
				(type default)
			)
			(layer "F.SilkS")
		)
		(fp_line
			(start 0.7874 0.4064)
			(end -0.7874 0.4064)
			(stroke
				(width 0.1524)
				(type default)
			)
			(layer "F.SilkS")
		)
		(fp_line
			(start -0.7874 -0.4064)
			(end 0.7874 -0.4064)
			(stroke
				(width 0.1524)
				(type default)
			)
			(layer "F.SilkS")
		)
		(fp_line
			(start 0.7874 -0.4064)
			(end 0.7874 0.4064)
			(stroke
				(width 0.1524)
				(type default)
			)
			(layer "F.SilkS")
		)
		(fp_poly
			(pts
				(xy -0.508 0.2794) (xy -0.508 0.2286) (xy -0.635 0.2286) (xy -0.635 -0.254) (xy -0.5334 -0.254)
				(xy -0.5334 -0.2794) (xy 0.5334 -0.2794) (xy 0.5334 -0.254) (xy 0.635 -0.254) (xy 0.635 0.254) (xy 0.5334 0.254)
				(xy 0.5334 0.2794)
			)
			(stroke
				(width 0)
				(type default)
			)
			(fill no)
			(layer "F.CrtYd")
		)
		(pad "1" smd rect
			(at 0.40005 0 270)
			(size 0.4572 0.508)
			(layers "F.Cu" "F.Mask" "F.Paste")
			(net "UART_T2_NODE4_TXD")
		)
		(pad "2" smd rect
			(at -0.40005 0 270)
			(size 0.4572 0.508)
			(layers "F.Cu" "F.Mask" "F.Paste")
			(net "UART_T2_NODE4_TXD_R")
		)
	)
	(footprint ""
		(layer "F.Cu")
		(at 125.018292 -161.189162)
		(property "Reference" "R665"
			(at 29.279088 46.827694 0)
			(unlocked yes)
			(layer "F.SilkS")
			(effects
				(font
					(size 0.7874 0.5842)
					(thickness 0.1524)
				)
				(justify left)
			)
		)
		(property "Value" ""
			(at 0 0 0)
			(layer "F.Fab")
			(effects
				(font
					(size 1.27 1.27)
				)
			)
		)
		(duplicate_pad_numbers_are_jumpers no)
		(fp_line
			(start -0.7874 -0.4064)
			(end 0.7874 -0.4064)
			(stroke
				(width 0.1524)
				(type default)
			)
			(layer "F.SilkS")
		)
		(fp_line
			(start -0.7874 0.4064)
			(end -0.7874 -0.4064)
			(stroke
				(width 0.1524)
				(type default)
			)
			(layer "F.SilkS")
		)
		(fp_line
			(start 0.7874 -0.4064)
			(end 0.7874 0.4064)
			(stroke
				(width 0.1524)
				(type default)
			)
			(layer "F.SilkS")
		)
		(fp_line
			(start 0.7874 0.4064)
			(end -0.7874 0.4064)
			(stroke
				(width 0.1524)
				(type default)
			)
			(layer "F.SilkS")
		)
		(fp_poly
			(pts
				(xy -0.508 0.2794) (xy -0.508 0.2286) (xy -0.635 0.2286) (xy -0.635 -0.254) (xy -0.5334 -0.254)
				(xy -0.5334 -0.2794) (xy 0.5334 -0.2794) (xy 0.5334 -0.254) (xy 0.635 -0.254) (xy 0.635 0.254) (xy 0.5334 0.254)
				(xy 0.5334 0.2794)
			)
			(stroke
				(width 0)
				(type default)
			)
			(fill no)
			(layer "F.CrtYd")
		)
		(pad "1" smd rect
			(at 0.40005 0)
			(size 0.4572 0.508)
			(layers "F.Cu" "F.Mask" "F.Paste")
			(net "P3V3_NODE1")
		)
		(pad "2" smd rect
			(at -0.40005 0)
			(size 0.4572 0.508)
			(layers "F.Cu" "F.Mask" "F.Paste")
			(net "I2C_PSU1_SCL_MOS")
		)
	)
	(footprint ""
		(layer "F.Cu")
		(at 95.195644 -130.052318 90)
		(property "Reference" "C810"
			(at -4.296918 -0.489458 90)
			(unlocked yes)
			(layer "F.SilkS")
			(effects
				(font
					(size 0.635 0.4064)
					(thickness 0.1524)
				)
				(justify left)
			)
		)
		(property "Value" ""
			(at 0 0 90)
			(layer "F.Fab")
			(effects
				(font
					(size 1.27 1.27)
				)
			)
		)
		(duplicate_pad_numbers_are_jumpers no)
		(fp_line
			(start 1.905 -0.8636)
			(end 1.905 0.8636)
			(stroke
				(width 0.1524)
				(type default)
			)
			(layer "F.SilkS")
		)
		(fp_line
			(start -1.905 -0.8636)
			(end 1.905 -0.8636)
			(stroke
				(width 0.1524)
				(type default)
			)
			(layer "F.SilkS")
		)
		(fp_line
			(start 0 0.8382)
			(end 0 -0.8382)
			(stroke
				(width 0.1524)
				(type default)
			)
			(layer "F.SilkS")
		)
		(fp_line
			(start 1.905 0.8636)
			(end -1.905 0.8636)
			(stroke
				(width 0.1524)
				(type default)
			)
			(layer "F.SilkS")
		)
		(fp_line
			(start -1.905 0.8636)
			(end -1.905 -0.8636)
			(stroke
				(width 0.1524)
				(type default)
			)
			(layer "F.SilkS")
		)
		(fp_rect
			(start -1.524 0.7366)
			(end 1.524 -0.7366)
			(stroke
				(width 0)
				(type default)
			)
			(fill no)
			(layer "F.CrtYd")
		)
		(pad "1" smd rect
			(at 0.94996 0 90)
			(size 1.1176 1.3716)
			(layers "F.Cu" "F.Mask" "F.Paste")
			(net "P1V8_STB_NODE1")
		)
		(pad "2" smd rect
			(at -0.94996 0 90)
			(size 1.1176 1.3716)
			(layers "F.Cu" "F.Mask" "F.Paste")
			(net "GND")
		)
	)
	(footprint ""
		(layer "F.Cu")
		(at 107.82554 -174.098458)
		(property "Reference" "C574"
			(at -1.15824 -1.26111 0)
			(unlocked yes)
			(layer "F.SilkS")
			(effects
				(font
					(size 0.7874 0.5842)
					(thickness 0.1524)
				)
				(justify left)
			)
		)
		(property "Value" ""
			(at 0 0 0)
			(layer "F.Fab")
			(effects
				(font
					(size 1.27 1.27)
				)
			)
		)
		(duplicate_pad_numbers_are_jumpers no)
		(fp_line
			(start -0.7874 -0.4064)
			(end 0.7874 -0.4064)
			(stroke
				(width 0.1524)
				(type default)
			)
			(layer "F.SilkS")
		)
		(fp_line
			(start -0.7874 0.4064)
			(end -0.7874 -0.4064)
			(stroke
				(width 0.1524)
				(type default)
			)
			(layer "F.SilkS")
		)
		(fp_line
			(start 0 0.381)
			(end 0 -0.381)
			(stroke
				(width 0.1524)
				(type default)
			)
			(layer "F.SilkS")
		)
		(fp_line
			(start 0.7874 -0.4064)
			(end 0.7874 0.4064)
			(stroke
				(width 0.1524)
				(type default)
			)
			(layer "F.SilkS")
		)
		(fp_line
			(start 0.7874 0.4064)
			(end -0.7874 0.4064)
			(stroke
				(width 0.1524)
				(type default)
			)
			(layer "F.SilkS")
		)
		(fp_poly
			(pts
				(xy -0.5334 0.254) (xy -0.635 0.254) (xy -0.635 0.2286) (xy -0.635 -0.254) (xy -0.5334 -0.254) (xy -0.5334 -0.2794)
				(xy 0.5334 -0.2794) (xy 0.5334 -0.254) (xy 0.635 -0.254) (xy 0.635 0.254) (xy 0.5334 0.254) (xy 0.5334 0.2794)
				(xy -0.508 0.2794) (xy -0.5334 0.2794)
			)
			(stroke
				(width 0)
				(type default)
			)
			(fill no)
			(layer "F.CrtYd")
		)
		(pad "1" smd rect
			(at 0.40005 0)
			(size 0.4572 0.508)
			(layers "F.Cu" "F.Mask" "F.Paste")
			(net "P3V3_NODE1")
		)
		(pad "2" smd rect
			(at -0.40005 0)
			(size 0.4572 0.508)
			(layers "F.Cu" "F.Mask" "F.Paste")
			(net "GND")
		)
	)
)
